(kicad_pcb
	(version 20260206)
	(generator "pcbnew")
	(generator_version "10.0")
	(general
		(thickness 1.6)
		(legacy_teardrops no)
	)
	(paper "A4")
	(title_block
		(title "04192023_DAF0TMB3IC0_F0TG_MB_C_brd_V02_OCP.brd")
		(comment 1 "Grand Teton / footprint 2783 of 8354 (U26), pads 2561-2670 of 6102")
	)
	(layers
		(0 "F.Cu" signal "TOP")
		(4 "In1.Cu" signal "GND")
		(6 "In2.Cu" signal "IN1")
		(8 "In3.Cu" signal "GND1")
		(10 "In4.Cu" signal "IN2")
		(12 "In5.Cu" signal "GND2")
		(14 "In6.Cu" signal "IN3")
		(16 "In7.Cu" signal "GND3")
		(18 "In8.Cu" signal "VCC")
		(20 "In9.Cu" signal "VCC1")
		(22 "In10.Cu" signal "GND4")
		(24 "In11.Cu" signal "IN4")
		(26 "In12.Cu" signal "GND5")
		(28 "In13.Cu" signal "IN5")
		(30 "In14.Cu" signal "GND6")
		(32 "In15.Cu" signal "IN6")
		(34 "In16.Cu" signal "GND7")
		(2 "B.Cu" signal "BOTTOM")
		(9 "F.Adhes" user "F.Adhesive")
		(11 "B.Adhes" user "B.Adhesive")
		(13 "F.Paste" user "Package Geometry/Pastemask Top")
		(15 "B.Paste" user "Package Geometry/Pastemask Bottom")
		(5 "F.SilkS" user "Ref Des/Silkscreen Top")
		(7 "B.SilkS" user "Ref Des/Silkscreen Bottom")
		(1 "F.Mask" user "Board Geometry/Soldermask Top")
		(3 "B.Mask" user "Board Geometry/Soldermask Bottom")
		(17 "Dwgs.User" user "User.Drawings")
		(19 "Cmts.User" user "User.Comments")
		(21 "Eco1.User" user "User.Eco1")
		(23 "Eco2.User" user "User.Eco2")
		(25 "Edge.Cuts" user "Board Geometry/Outline")
		(27 "Margin" user)
		(31 "F.CrtYd" user "Package Geometry/Place Bound Top")
		(29 "B.CrtYd" user "Package Geometry/Place Bound Bottom")
		(35 "F.Fab" user "Ref Des/Assembly Top")
		(33 "B.Fab" user "Ref Des/Assembly Bottom")
	)
	(footprint ""
		(layer "F.Cu")
		(at 111.927894 -258.880356 180)
		(property "Reference" "U26"
			(at -45.05579 -61.794136 0)
			(unlocked yes)
			(layer "F.SilkS")
			(effects
				(font
					(size 0.7874 0.5842)
					(thickness 0.1524)
				)
			)
		)
		(property "Value" ""
			(at 0 0 180)
			(layer "F.Fab")
			(effects
				(font
					(size 1.27 1.27)
				)
			)
		)
		(duplicate_pad_numbers_are_jumpers no)
		(pad "BV43" smd circle
			(at 4.549902 11.700002 180)
			(size 0.450088 0.450088)
			(layers "F.Cu" "F.Mask" "F.Paste")
			(net "GND")
		)
		(pad "BV44" smd circle
			(at 5.489956 11.700002 180)
			(size 0.450088 0.450088)
			(layers "F.Cu" "F.Mask" "F.Paste")
			(net "GND")
		)
		(pad "BV45" smd circle
			(at 6.43001 11.700002 180)
			(size 0.450088 0.450088)
			(layers "F.Cu" "F.Mask" "F.Paste")
			(net "GND")
		)
		(pad "BV46" smd circle
			(at 7.370064 11.700002 180)
			(size 0.450088 0.450088)
			(layers "F.Cu" "F.Mask" "F.Paste")
			(net "GND")
		)
		(pad "BV47" smd circle
			(at 8.310118 11.700002 180)
			(size 0.450088 0.450088)
			(layers "F.Cu" "F.Mask" "F.Paste")
			(net "GND")
		)
		(pad "BV48" smd circle
			(at 9.249918 11.700002 180)
			(size 0.450088 0.450088)
			(layers "F.Cu" "F.Mask" "F.Paste")
			(net "GND")
		)
		(pad "BV49" smd circle
			(at 10.189972 11.700002 180)
			(size 0.450088 0.450088)
			(layers "F.Cu" "F.Mask" "F.Paste")
			(net "GND")
		)
		(pad "BV50" smd circle
			(at 11.130026 11.700002 180)
			(size 0.450088 0.450088)
			(layers "F.Cu" "F.Mask" "F.Paste")
			(net "GND")
		)
		(pad "BV51" smd circle
			(at 12.07008 11.700002 180)
			(size 0.450088 0.450088)
			(layers "F.Cu" "F.Mask" "F.Paste")
			(net "GND")
		)
		(pad "BV52" smd circle
			(at 13.00988 11.700002 180)
			(size 0.450088 0.450088)
			(layers "F.Cu" "F.Mask" "F.Paste")
			(net "GND")
		)
		(pad "BV53" smd circle
			(at 13.949934 11.700002 180)
			(size 0.450088 0.450088)
			(layers "F.Cu" "F.Mask" "F.Paste")
			(net "GND")
		)
		(pad "BV54" smd circle
			(at 14.889988 11.700002 180)
			(size 0.450088 0.450088)
			(layers "F.Cu" "F.Mask" "F.Paste")
			(net "PVDDIO_P1")
		)
		(pad "BV55" smd circle
			(at 15.830042 11.700002 180)
			(size 0.450088 0.450088)
			(layers "F.Cu" "F.Mask" "F.Paste")
			(net "M_C_CPU1_SB_CB<7>")
		)
		(pad "BV56" smd circle
			(at 16.770096 11.700002 180)
			(size 0.450088 0.450088)
			(layers "F.Cu" "F.Mask" "F.Paste")
			(net "M_C_CPU1_SB_DQS_DP<9>")
		)
		(pad "BV57" smd circle
			(at 17.709896 11.700002 180)
			(size 0.450088 0.450088)
			(layers "F.Cu" "F.Mask" "F.Paste")
			(net "PVDDIO_P1")
		)
		(pad "BV58" smd circle
			(at 18.64995 11.700002 180)
			(size 0.450088 0.450088)
			(layers "F.Cu" "F.Mask" "F.Paste")
			(net "M_D_CPU1_SB_CB<7>")
		)
		(pad "BV59" smd circle
			(at 19.590004 11.700002 180)
			(size 0.450088 0.450088)
			(layers "F.Cu" "F.Mask" "F.Paste")
			(net "GND")
		)
		(pad "BV60" smd circle
			(at 20.530058 11.700002 180)
			(size 0.450088 0.450088)
			(layers "F.Cu" "F.Mask" "F.Paste")
			(net "M_D_CPU1_SB_DQS_DP<9>")
		)
		(pad "BV61" smd circle
			(at 21.470112 11.700002 180)
			(size 0.450088 0.450088)
			(layers "F.Cu" "F.Mask" "F.Paste")
			(net "GND")
		)
		(pad "BV62" smd circle
			(at 22.409912 11.700002 180)
			(size 0.450088 0.450088)
			(layers "F.Cu" "F.Mask" "F.Paste")
			(net "M_B_CPU1_SB_CB<7>")
		)
		(pad "BV63" smd circle
			(at 23.349966 11.700002 180)
			(size 0.450088 0.450088)
			(layers "F.Cu" "F.Mask" "F.Paste")
			(net "M_B_CPU1_SB_DQS_DP<9>")
		)
		(pad "BV64" smd circle
			(at 24.29002 11.700002 180)
			(size 0.450088 0.450088)
			(layers "F.Cu" "F.Mask" "F.Paste")
			(net "PVDDIO_P1")
		)
		(pad "BV65" smd circle
			(at 25.230074 11.700002 180)
			(size 0.450088 0.450088)
			(layers "F.Cu" "F.Mask" "F.Paste")
			(net "M_F_CPU1_SB_CB<7>")
		)
		(pad "BV66" smd circle
			(at 26.170128 11.700002 180)
			(size 0.450088 0.450088)
			(layers "F.Cu" "F.Mask" "F.Paste")
			(net "GND")
		)
		(pad "BV67" smd circle
			(at 27.109928 11.700002 180)
			(size 0.450088 0.450088)
			(layers "F.Cu" "F.Mask" "F.Paste")
			(net "M_F_CPU1_SB_DQS_DP<9>")
		)
		(pad "BV68" smd circle
			(at 28.049982 11.700002 180)
			(size 0.450088 0.450088)
			(layers "F.Cu" "F.Mask" "F.Paste")
			(net "GND")
		)
		(pad "BV69" smd circle
			(at 28.990036 11.700002 180)
			(size 0.450088 0.450088)
			(layers "F.Cu" "F.Mask" "F.Paste")
			(net "M_E_CPU1_SB_CB<7>")
		)
		(pad "BV70" smd circle
			(at 29.93009 11.700002 180)
			(size 0.450088 0.450088)
			(layers "F.Cu" "F.Mask" "F.Paste")
			(net "M_E_CPU1_SB_DQS_DP<9>")
		)
		(pad "BV71" smd circle
			(at 30.86989 11.700002 180)
			(size 0.450088 0.450088)
			(layers "F.Cu" "F.Mask" "F.Paste")
			(net "PVDDIO_P1")
		)
		(pad "BV72" smd circle
			(at 31.809944 11.700002 180)
			(size 0.450088 0.450088)
			(layers "F.Cu" "F.Mask" "F.Paste")
			(net "M_A_CPU1_SB_CB<7>")
		)
		(pad "BV73" smd circle
			(at 32.749998 11.700002 180)
			(size 0.450088 0.450088)
			(layers "F.Cu" "F.Mask" "F.Paste")
			(net "GND")
		)
		(pad "BV74" smd circle
			(at 33.690052 11.700002 180)
			(size 0.450088 0.450088)
			(layers "F.Cu" "F.Mask" "F.Paste")
			(net "M_A_CPU1_SB_DQS_DP<9>")
		)
		(pad "BW1" smd circle
			(at -34.459926 12.510008 180)
			(size 0.450088 0.450088)
			(layers "F.Cu" "F.Mask" "F.Paste")
			(net "GND")
		)
		(pad "BW2" smd circle
			(at -33.519872 12.510008 180)
			(size 0.450088 0.450088)
			(layers "F.Cu" "F.Mask" "F.Paste")
			(net "M_G_CPU1_SB_DQS_DN<9>")
		)
		(pad "BW3" smd circle
			(at -32.580072 12.510008 180)
			(size 0.450088 0.450088)
			(layers "F.Cu" "F.Mask" "F.Paste")
			(net "M_G_CPU1_SB_DQS_DN<4>")
		)
		(pad "BW4" smd circle
			(at -31.640018 12.510008 180)
			(size 0.450088 0.450088)
			(layers "F.Cu" "F.Mask" "F.Paste")
			(net "GND")
		)
		(pad "BW5" smd circle
			(at -30.699964 12.510008 180)
			(size 0.450088 0.450088)
			(layers "F.Cu" "F.Mask" "F.Paste")
			(net "M_K_CPU1_SB_DQS_DN<9>")
		)
		(pad "BW6" smd circle
			(at -29.75991 12.510008 180)
			(size 0.450088 0.450088)
			(layers "F.Cu" "F.Mask" "F.Paste")
			(net "GND")
		)
		(pad "BW7" smd circle
			(at -28.82011 12.510008 180)
			(size 0.450088 0.450088)
			(layers "F.Cu" "F.Mask" "F.Paste")
			(net "M_K_CPU1_SB_DQS_DN<4>")
		)
		(pad "BW8" smd circle
			(at -27.880056 12.510008 180)
			(size 0.450088 0.450088)
			(layers "F.Cu" "F.Mask" "F.Paste")
			(net "GND")
		)
		(pad "BW9" smd circle
			(at -26.940002 12.510008 180)
			(size 0.450088 0.450088)
			(layers "F.Cu" "F.Mask" "F.Paste")
			(net "M_L_CPU1_SB_DQS_DN<9>")
		)
		(pad "BW10" smd circle
			(at -25.999948 12.510008 180)
			(size 0.450088 0.450088)
			(layers "F.Cu" "F.Mask" "F.Paste")
			(net "M_L_CPU1_SB_DQS_DN<4>")
		)
		(pad "BW11" smd circle
			(at -25.059894 12.510008 180)
			(size 0.450088 0.450088)
			(layers "F.Cu" "F.Mask" "F.Paste")
			(net "GND")
		)
		(pad "BW12" smd circle
			(at -24.120094 12.510008 180)
			(size 0.450088 0.450088)
			(layers "F.Cu" "F.Mask" "F.Paste")
			(net "M_H_CPU1_SB_DQS_DN<9>")
		)
		(pad "BW13" smd circle
			(at -23.18004 12.510008 180)
			(size 0.450088 0.450088)
			(layers "F.Cu" "F.Mask" "F.Paste")
			(net "GND")
		)
		(pad "BW14" smd circle
			(at -22.239986 12.510008 180)
			(size 0.450088 0.450088)
			(layers "F.Cu" "F.Mask" "F.Paste")
			(net "M_H_CPU1_SB_DQS_DN<4>")
		)
		(pad "BW15" smd circle
			(at -21.299932 12.510008 180)
			(size 0.450088 0.450088)
			(layers "F.Cu" "F.Mask" "F.Paste")
			(net "GND")
		)
		(pad "BW16" smd circle
			(at -20.359878 12.510008 180)
			(size 0.450088 0.450088)
			(layers "F.Cu" "F.Mask" "F.Paste")
			(net "M_J_CPU1_SB_DQS_DN<9>")
		)
		(pad "BW17" smd circle
			(at -19.420078 12.510008 180)
			(size 0.450088 0.450088)
			(layers "F.Cu" "F.Mask" "F.Paste")
			(net "M_J_CPU1_SB_DQS_DN<4>")
		)
		(pad "BW18" smd circle
			(at -18.480024 12.510008 180)
			(size 0.450088 0.450088)
			(layers "F.Cu" "F.Mask" "F.Paste")
			(net "GND")
		)
		(pad "BW19" smd circle
			(at -17.53997 12.510008 180)
			(size 0.450088 0.450088)
			(layers "F.Cu" "F.Mask" "F.Paste")
			(net "M_I_CPU1_SB_DQS_DN<9>")
		)
		(pad "BW20" smd circle
			(at -16.599916 12.510008 180)
			(size 0.450088 0.450088)
			(layers "F.Cu" "F.Mask" "F.Paste")
			(net "GND")
		)
		(pad "BW21" smd circle
			(at -15.660116 12.510008 180)
			(size 0.450088 0.450088)
			(layers "F.Cu" "F.Mask" "F.Paste")
			(net "M_I_CPU1_SB_DQS_DN<4>")
		)
		(pad "BW22" smd circle
			(at -14.720062 12.510008 180)
			(size 0.450088 0.450088)
			(layers "F.Cu" "F.Mask" "F.Paste")
			(net "GND")
		)
		(pad "BW23" smd circle
			(at -13.780008 12.510008 180)
			(size 0.450088 0.450088)
			(layers "F.Cu" "F.Mask" "F.Paste")
			(net "P5E_CPU1_P2_TX_DN<15>")
		)
		(pad "BW24" smd circle
			(at -12.839954 12.510008 180)
			(size 0.450088 0.450088)
			(layers "F.Cu" "F.Mask" "F.Paste")
			(net "P5E_CPU1_P2_TX_DP<15>")
		)
		(pad "BW25" smd circle
			(at -11.8999 12.510008 180)
			(size 0.450088 0.450088)
			(layers "F.Cu" "F.Mask" "F.Paste")
			(net "GND")
		)
		(pad "BW26" smd circle
			(at -10.9601 12.510008 180)
			(size 0.450088 0.450088)
			(layers "F.Cu" "F.Mask" "F.Paste")
			(net "P5E_CPU1_P2_TX_DN<12>")
		)
		(pad "BW27" smd circle
			(at -10.020046 12.510008 180)
			(size 0.450088 0.450088)
			(layers "F.Cu" "F.Mask" "F.Paste")
			(net "P5E_CPU1_P2_TX_DP<12>")
		)
		(pad "BW28" smd circle
			(at -9.079992 12.510008 180)
			(size 0.450088 0.450088)
			(layers "F.Cu" "F.Mask" "F.Paste")
			(net "GND")
		)
		(pad "BW29" smd circle
			(at -8.139938 12.510008 180)
			(size 0.450088 0.450088)
			(layers "F.Cu" "F.Mask" "F.Paste")
			(net "P5E_CPU1_P2_TX_DN<9>")
		)
		(pad "BW30" smd circle
			(at -7.199884 12.510008 180)
			(size 0.450088 0.450088)
			(layers "F.Cu" "F.Mask" "F.Paste")
			(net "P5E_CPU1_P2_TX_DP<9>")
		)
		(pad "BW31" smd circle
			(at -6.260084 12.510008 180)
			(size 0.450088 0.450088)
			(layers "F.Cu" "F.Mask" "F.Paste")
			(net "GND")
		)
		(pad "BW32" smd circle
			(at -5.32003 12.510008 180)
			(size 0.450088 0.450088)
			(layers "F.Cu" "F.Mask" "F.Paste")
			(net "P5E_CPU1_P2_TX_DN<6>")
		)
		(pad "BW33" smd circle
			(at -4.379976 12.510008 180)
			(size 0.450088 0.450088)
			(layers "F.Cu" "F.Mask" "F.Paste")
			(net "P5E_CPU1_P2_TX_DP<6>")
		)
		(pad "BW34" smd circle
			(at -3.439922 12.510008 180)
			(size 0.450088 0.450088)
			(layers "F.Cu" "F.Mask" "F.Paste")
			(net "GND")
		)
		(pad "BW35" smd circle
			(at -2.500122 12.510008 180)
			(size 0.450088 0.450088)
			(layers "F.Cu" "F.Mask" "F.Paste")
			(net "PVDDCR_CPU1_P1")
		)
		(pad "BW36" smd circle
			(at -1.560068 12.510008 180)
			(size 0.450088 0.450088)
			(layers "F.Cu" "F.Mask" "F.Paste")
			(net "PVDDCR_CPU1_P1")
		)
		(pad "BW40" smd circle
			(at 1.260094 12.510008 180)
			(size 0.450088 0.450088)
			(layers "F.Cu" "F.Mask" "F.Paste")
			(net "PVDDCR_CPU1_P1")
		)
		(pad "BW41" smd circle
			(at 2.199894 12.510008 180)
			(size 0.450088 0.450088)
			(layers "F.Cu" "F.Mask" "F.Paste")
			(net "PVDDCR_CPU1_P1")
		)
		(pad "BW42" smd circle
			(at 3.139948 12.510008 180)
			(size 0.450088 0.450088)
			(layers "F.Cu" "F.Mask" "F.Paste")
			(net "GND")
		)
		(pad "BW43" smd circle
			(at 4.080002 12.510008 180)
			(size 0.450088 0.450088)
			(layers "F.Cu" "F.Mask" "F.Paste")
			(net "P5E_CPU1_P0_RX_DP<9>")
		)
		(pad "BW44" smd circle
			(at 5.020056 12.510008 180)
			(size 0.450088 0.450088)
			(layers "F.Cu" "F.Mask" "F.Paste")
			(net "P5E_CPU1_P0_RX_DN<9>")
		)
		(pad "BW45" smd circle
			(at 5.96011 12.510008 180)
			(size 0.450088 0.450088)
			(layers "F.Cu" "F.Mask" "F.Paste")
			(net "GND")
		)
		(pad "BW46" smd circle
			(at 6.89991 12.510008 180)
			(size 0.450088 0.450088)
			(layers "F.Cu" "F.Mask" "F.Paste")
			(net "P5E_CPU1_P0_RX_DP<6>")
		)
		(pad "BW47" smd circle
			(at 7.839964 12.510008 180)
			(size 0.450088 0.450088)
			(layers "F.Cu" "F.Mask" "F.Paste")
			(net "P5E_CPU1_P0_RX_DN<6>")
		)
		(pad "BW48" smd circle
			(at 8.780018 12.510008 180)
			(size 0.450088 0.450088)
			(layers "F.Cu" "F.Mask" "F.Paste")
			(net "GND")
		)
		(pad "BW49" smd circle
			(at 9.720072 12.510008 180)
			(size 0.450088 0.450088)
			(layers "F.Cu" "F.Mask" "F.Paste")
			(net "P5E_CPU1_P0_RX_DP<3>")
		)
		(pad "BW50" smd circle
			(at 10.659872 12.510008 180)
			(size 0.450088 0.450088)
			(layers "F.Cu" "F.Mask" "F.Paste")
			(net "P5E_CPU1_P0_RX_DN<3>")
		)
		(pad "BW51" smd circle
			(at 11.599926 12.510008 180)
			(size 0.450088 0.450088)
			(layers "F.Cu" "F.Mask" "F.Paste")
			(net "GND")
		)
		(pad "BW52" smd circle
			(at 12.53998 12.510008 180)
			(size 0.450088 0.450088)
			(layers "F.Cu" "F.Mask" "F.Paste")
			(net "P5E_CPU1_P0_RX_DP<0>")
		)
		(pad "BW53" smd circle
			(at 13.480034 12.510008 180)
			(size 0.450088 0.450088)
			(layers "F.Cu" "F.Mask" "F.Paste")
			(net "P5E_CPU1_P0_RX_DN<0>")
		)
		(pad "BW54" smd circle
			(at 14.420088 12.510008 180)
			(size 0.450088 0.450088)
			(layers "F.Cu" "F.Mask" "F.Paste")
			(net "GND")
		)
		(pad "BW55" smd circle
			(at 15.359888 12.510008 180)
			(size 0.450088 0.450088)
			(layers "F.Cu" "F.Mask" "F.Paste")
			(net "M_C_CPU1_SB_DQS_DN<4>")
		)
		(pad "BW56" smd circle
			(at 16.299942 12.510008 180)
			(size 0.450088 0.450088)
			(layers "F.Cu" "F.Mask" "F.Paste")
			(net "GND")
		)
		(pad "BW57" smd circle
			(at 17.239996 12.510008 180)
			(size 0.450088 0.450088)
			(layers "F.Cu" "F.Mask" "F.Paste")
			(net "M_C_CPU1_SB_DQS_DN<9>")
		)
		(pad "BW58" smd circle
			(at 18.18005 12.510008 180)
			(size 0.450088 0.450088)
			(layers "F.Cu" "F.Mask" "F.Paste")
			(net "GND")
		)
		(pad "BW59" smd circle
			(at 19.120104 12.510008 180)
			(size 0.450088 0.450088)
			(layers "F.Cu" "F.Mask" "F.Paste")
			(net "M_D_CPU1_SB_DQS_DN<4>")
		)
		(pad "BW60" smd circle
			(at 20.059904 12.510008 180)
			(size 0.450088 0.450088)
			(layers "F.Cu" "F.Mask" "F.Paste")
			(net "M_D_CPU1_SB_DQS_DN<9>")
		)
		(pad "BW61" smd circle
			(at 20.999958 12.510008 180)
			(size 0.450088 0.450088)
			(layers "F.Cu" "F.Mask" "F.Paste")
			(net "GND")
		)
		(pad "BW62" smd circle
			(at 21.940012 12.510008 180)
			(size 0.450088 0.450088)
			(layers "F.Cu" "F.Mask" "F.Paste")
			(net "M_B_CPU1_SB_DQS_DN<4>")
		)
		(pad "BW63" smd circle
			(at 22.880066 12.510008 180)
			(size 0.450088 0.450088)
			(layers "F.Cu" "F.Mask" "F.Paste")
			(net "GND")
		)
		(pad "BW64" smd circle
			(at 23.82012 12.510008 180)
			(size 0.450088 0.450088)
			(layers "F.Cu" "F.Mask" "F.Paste")
			(net "M_B_CPU1_SB_DQS_DN<9>")
		)
		(pad "BW65" smd circle
			(at 24.75992 12.510008 180)
			(size 0.450088 0.450088)
			(layers "F.Cu" "F.Mask" "F.Paste")
			(net "GND")
		)
		(pad "BW66" smd circle
			(at 25.699974 12.510008 180)
			(size 0.450088 0.450088)
			(layers "F.Cu" "F.Mask" "F.Paste")
			(net "M_F_CPU1_SB_DQS_DN<4>")
		)
		(pad "BW67" smd circle
			(at 26.640028 12.510008 180)
			(size 0.450088 0.450088)
			(layers "F.Cu" "F.Mask" "F.Paste")
			(net "M_F_CPU1_SB_DQS_DN<9>")
		)
		(pad "BW68" smd circle
			(at 27.580082 12.510008 180)
			(size 0.450088 0.450088)
			(layers "F.Cu" "F.Mask" "F.Paste")
			(net "GND")
		)
		(pad "BW69" smd circle
			(at 28.519882 12.510008 180)
			(size 0.450088 0.450088)
			(layers "F.Cu" "F.Mask" "F.Paste")
			(net "M_E_CPU1_SB_DQS_DN<4>")
		)
		(pad "BW70" smd circle
			(at 29.459936 12.510008 180)
			(size 0.450088 0.450088)
			(layers "F.Cu" "F.Mask" "F.Paste")
			(net "GND")
		)
		(pad "BW71" smd circle
			(at 30.39999 12.510008 180)
			(size 0.450088 0.450088)
			(layers "F.Cu" "F.Mask" "F.Paste")
			(net "M_E_CPU1_SB_DQS_DN<9>")
		)
		(pad "BW72" smd circle
			(at 31.340044 12.510008 180)
			(size 0.450088 0.450088)
			(layers "F.Cu" "F.Mask" "F.Paste")
			(net "GND")
		)
		(pad "BW73" smd circle
			(at 32.280098 12.510008 180)
			(size 0.450088 0.450088)
			(layers "F.Cu" "F.Mask" "F.Paste")
			(net "M_A_CPU1_SB_DQS_DN<4>")
		)
		(pad "BW74" smd circle
			(at 33.219898 12.510008 180)
			(size 0.450088 0.450088)
			(layers "F.Cu" "F.Mask" "F.Paste")
			(net "M_A_CPU1_SB_DQS_DN<9>")
		)
		(pad "BW75" smd circle
			(at 34.159952 12.510008 180)
			(size 0.450088 0.450088)
			(layers "F.Cu" "F.Mask" "F.Paste")
			(net "GND")
		)
		(pad "BY2" smd circle
			(at -33.990026 13.320014 180)
			(size 0.450088 0.450088)
			(layers "F.Cu" "F.Mask" "F.Paste")
			(net "M_G_CPU1_SB_CB<0>")
		)
		(pad "BY3" smd circle
			(at -33.049972 13.320014 180)
			(size 0.450088 0.450088)
			(layers "F.Cu" "F.Mask" "F.Paste")
			(net "GND")
		)
		(pad "BY4" smd circle
			(at -32.109918 13.320014 180)
			(size 0.450088 0.450088)
			(layers "F.Cu" "F.Mask" "F.Paste")
			(net "M_G_CPU1_SB_DQS_DP<4>")
		)
		(pad "BY5" smd circle
			(at -31.170118 13.320014 180)
			(size 0.450088 0.450088)
			(layers "F.Cu" "F.Mask" "F.Paste")
			(net "GND")
		)
		(pad "BY6" smd circle
			(at -30.230064 13.320014 180)
			(size 0.450088 0.450088)
			(layers "F.Cu" "F.Mask" "F.Paste")
			(net "M_K_CPU1_SB_CB<0>")
		)
		(pad "BY7" smd circle
			(at -29.29001 13.320014 180)
			(size 0.450088 0.450088)
			(layers "F.Cu" "F.Mask" "F.Paste")
			(net "M_K_CPU1_SB_DQS_DP<4>")
		)
	)
)
